# S9S_MB_2U (Grand Teton) — schematic netlist excerpt (pin names and nets, part order shuffled) for the footprints in the layout excerpt that follows; sources: Cadence DE-HDL packaged netlist, KiCad conversion of 03242023_DA0F0TMBIJ0_F0T_Motherboard_J_brd_V01_OCP.brd

R95  Q_RES  240 1% EMPTY  pkg 0402LF  page 126 : A = PVNN_TERM_CPU0 ; B = PU_CPU0_UPI1_AC_COUPLING
C1308  Q_CAP  1000PF 50V 5% EMPTY  pkg 0402  page 300 : A = FM_PVNN_MAIN_CPU1_EN ; B = GND

(kicad_pcb
	(version 20260206)
	(generator "pcbnew")
	(generator_version "10.0")
	(general
		(thickness 1.6)
		(legacy_teardrops no)
	)
	(paper "A4")
	(title_block
		(title "03242023_DA0F0TMBIJ0_F0T_Motherboard_J_brd_V01_OCP.brd")
		(comment 1 "Grand Teton / footprints 5197-5198 of 6105")
	)
	(layers
		(0 "F.Cu" signal "TOP")
		(4 "In1.Cu" signal "GND")
		(6 "In2.Cu" signal "IN1")
		(8 "In3.Cu" signal "GND1")
		(10 "In4.Cu" signal "IN2")
		(12 "In5.Cu" signal "GND2")
		(14 "In6.Cu" signal "IN3")
		(16 "In7.Cu" signal "GND3")
		(18 "In8.Cu" signal "VCC")
		(20 "In9.Cu" signal "VCC1")
		(22 "In10.Cu" signal "GND4")
		(24 "In11.Cu" signal "IN4")
		(26 "In12.Cu" signal "GND5")
		(28 "In13.Cu" signal "IN5")
		(30 "In14.Cu" signal "GND6")
		(32 "In15.Cu" signal "IN6")
		(34 "In16.Cu" signal "GND7")
		(2 "B.Cu" signal "BOTTOM")
		(9 "F.Adhes" user "F.Adhesive")
		(11 "B.Adhes" user "B.Adhesive")
		(13 "F.Paste" user "Package Geometry/Pastemask Top")
		(15 "B.Paste" user "Package Geometry/Pastemask Bottom")
		(5 "F.SilkS" user "Ref Des/Silkscreen Top")
		(7 "B.SilkS" user "Ref Des/Silkscreen Bottom")
		(1 "F.Mask" user "Board Geometry/Soldermask Top")
		(3 "B.Mask" user "Board Geometry/Soldermask Bottom")
		(17 "Dwgs.User" user "User.Drawings")
		(19 "Cmts.User" user "User.Comments")
		(21 "Eco1.User" user "User.Eco1")
		(23 "Eco2.User" user "User.Eco2")
		(25 "Edge.Cuts" user "Board Geometry/Outline")
		(27 "Margin" user)
		(31 "F.CrtYd" user "Package Geometry/Place Bound Top")
		(29 "B.CrtYd" user "Package Geometry/Place Bound Bottom")
		(35 "F.Fab" user "Ref Des/Assembly Top")
		(33 "B.Fab" user "Ref Des/Assembly Bottom")
	)
	(footprint ""
		(layer "B.Cu")
		(at 381.92583 -190.82131 -90)
		(property "Reference" "R95"
			(at 0 0 90)
			(layer "B.SilkS")
			(hide yes)
			(effects
				(font
					(size 1.27 1.27)
				)
				(justify mirror)
			)
		)
		(property "Value" ""
			(at 0 0 90)
			(layer "B.Fab")
			(effects
				(font
					(size 1.27 1.27)
				)
				(justify mirror)
			)
		)
		(duplicate_pad_numbers_are_jumpers no)
		(fp_line
			(start -0.7874 0.4064)
			(end 0.7874 0.4064)
			(stroke
				(width 0.1524)
				(type default)
			)
			(layer "B.SilkS")
		)
		(fp_line
			(start 0.7874 0.4064)
			(end 0.7874 -0.4064)
			(stroke
				(width 0.1524)
				(type default)
			)
			(layer "B.SilkS")
		)
		(fp_line
			(start -0.7874 -0.4064)
			(end -0.7874 0.4064)
			(stroke
				(width 0.1524)
				(type default)
			)
			(layer "B.SilkS")
		)
		(fp_line
			(start 0.7874 -0.4064)
			(end -0.7874 -0.4064)
			(stroke
				(width 0.1524)
				(type default)
			)
			(layer "B.SilkS")
		)
		(fp_line
			(start -0.67945 0.3048)
			(end -0.120396 0.3048)
			(stroke
				(width 0.1)
				(type default)
			)
			(layer "B.Fab")
		)
		(fp_line
			(start -0.120396 0.3048)
			(end -0.120396 0.2794)
			(stroke
				(width 0.1)
				(type default)
			)
			(layer "B.Fab")
		)
		(fp_line
			(start 0.12065 0.3048)
			(end 0.67945 0.3048)
			(stroke
				(width 0.1)
				(type default)
			)
			(layer "B.Fab")
		)
		(fp_line
			(start 0.67945 0.3048)
			(end 0.67945 -0.305054)
			(stroke
				(width 0.1)
				(type default)
			)
			(layer "B.Fab")
		)
		(fp_line
			(start -0.120396 0.2794)
			(end 0.12065 0.2794)
			(stroke
				(width 0.1)
				(type default)
			)
			(layer "B.Fab")
		)
		(fp_line
			(start 0.12065 0.2794)
			(end 0.12065 0.3048)
			(stroke
				(width 0.1)
				(type default)
			)
			(layer "B.Fab")
		)
		(fp_line
			(start -0.12065 -0.2794)
			(end -0.12065 -0.3048)
			(stroke
				(width 0.1)
				(type default)
			)
			(layer "B.Fab")
		)
		(fp_line
			(start 0.12065 -0.2794)
			(end -0.12065 -0.2794)
			(stroke
				(width 0.1)
				(type default)
			)
			(layer "B.Fab")
		)
		(fp_line
			(start -0.67945 -0.3048)
			(end -0.67945 0.3048)
			(stroke
				(width 0.1)
				(type default)
			)
			(layer "B.Fab")
		)
		(fp_line
			(start -0.12065 -0.3048)
			(end -0.67945 -0.3048)
			(stroke
				(width 0.1)
				(type default)
			)
			(layer "B.Fab")
		)
		(fp_line
			(start 0.12065 -0.305054)
			(end 0.12065 -0.2794)
			(stroke
				(width 0.1)
				(type default)
			)
			(layer "B.Fab")
		)
		(fp_line
			(start 0.67945 -0.305054)
			(end 0.12065 -0.305054)
			(stroke
				(width 0.1)
				(type default)
			)
			(layer "B.Fab")
		)
		(pad "1" smd circle
			(at 0.40005 0 90)
			(size 0 0)
			(layers "B.Cu" "B.Mask" "B.Paste")
			(net "PVNN_TERM_CPU0")
		)
		(pad "2" smd circle
			(at -0.40005 0 90)
			(size 0 0)
			(layers "B.Cu" "B.Mask" "B.Paste")
			(net "PU_CPU0_UPI1_AC_COUPLING")
		)
	)
	(footprint ""
		(layer "B.Cu")
		(at 20.566634 -176.423574 -90)
		(property "Reference" "C1308"
			(at 0 0 90)
			(layer "B.SilkS")
			(hide yes)
			(effects
				(font
					(size 1.27 1.27)
				)
				(justify mirror)
			)
		)
		(property "Value" ""
			(at 0 0 90)
			(layer "B.Fab")
			(effects
				(font
					(size 1.27 1.27)
				)
				(justify mirror)
			)
		)
		(duplicate_pad_numbers_are_jumpers no)
		(fp_line
			(start -0.7874 0.4064)
			(end 0.7874 0.4064)
			(stroke
				(width 0.1524)
				(type default)
			)
			(layer "B.SilkS")
		)
		(fp_line
			(start 0.7874 0.4064)
			(end 0.7874 -0.4064)
			(stroke
				(width 0.1524)
				(type default)
			)
			(layer "B.SilkS")
		)
		(fp_line
			(start -0.7874 -0.4064)
			(end -0.7874 0.4064)
			(stroke
				(width 0.1524)
				(type default)
			)
			(layer "B.SilkS")
		)
		(fp_line
			(start 0.7874 -0.4064)
			(end -0.7874 -0.4064)
			(stroke
				(width 0.1524)
				(type default)
			)
			(layer "B.SilkS")
		)
		(fp_line
			(start -0.67945 0.3048)
			(end -0.120396 0.3048)
			(stroke
				(width 0.1)
				(type default)
			)
			(layer "B.Fab")
		)
		(fp_line
			(start -0.120396 0.3048)
			(end -0.120396 0.2794)
			(stroke
				(width 0.1)
				(type default)
			)
			(layer "B.Fab")
		)
		(fp_line
			(start 0.12065 0.3048)
			(end 0.67945 0.3048)
			(stroke
				(width 0.1)
				(type default)
			)
			(layer "B.Fab")
		)
		(fp_line
			(start 0.67945 0.3048)
			(end 0.67945 -0.305054)
			(stroke
				(width 0.1)
				(type default)
			)
			(layer "B.Fab")
		)
		(fp_line
			(start -0.120396 0.2794)
			(end 0.12065 0.2794)
			(stroke
				(width 0.1)
				(type default)
			)
			(layer "B.Fab")
		)
		(fp_line
			(start 0.12065 0.2794)
			(end 0.12065 0.3048)
			(stroke
				(width 0.1)
				(type default)
			)
			(layer "B.Fab")
		)
		(fp_line
			(start -0.12065 -0.2794)
			(end -0.12065 -0.3048)
			(stroke
				(width 0.1)
				(type default)
			)
			(layer "B.Fab")
		)
		(fp_line
			(start 0.12065 -0.2794)
			(end -0.12065 -0.2794)
			(stroke
				(width 0.1)
				(type default)
			)
			(layer "B.Fab")
		)
		(fp_line
			(start -0.67945 -0.3048)
			(end -0.67945 0.3048)
			(stroke
				(width 0.1)
				(type default)
			)
			(layer "B.Fab")
		)
		(fp_line
			(start -0.12065 -0.3048)
			(end -0.67945 -0.3048)
			(stroke
				(width 0.1)
				(type default)
			)
			(layer "B.Fab")
		)
		(fp_line
			(start 0.12065 -0.305054)
			(end 0.12065 -0.2794)
			(stroke
				(width 0.1)
				(type default)
			)
			(layer "B.Fab")
		)
		(fp_line
			(start 0.67945 -0.305054)
			(end 0.12065 -0.305054)
			(stroke
				(width 0.1)
				(type default)
			)
			(layer "B.Fab")
		)
		(pad "1" smd circle
			(at 0.40005 0 90)
			(size 0 0)
			(layers "B.Cu" "B.Mask" "B.Paste")
			(net "FM_PVNN_MAIN_CPU1_EN")
		)
		(pad "2" smd circle
			(at -0.40005 0 90)
			(size 0 0)
			(layers "B.Cu" "B.Mask" "B.Paste")
			(net "GND")
		)
	)
)
